(kicad_pcb
	(version 20241229)
	(generator "pcbnew")
	(generator_version "9.0")
	(general
		(thickness 1.6296)
		(legacy_teardrops no)
	)
	(paper "A3")
	(title_block
		(title "Thunderbolt to 10GbE adapter")
		(date "2026-04-21")
		(rev "1.1.0")
		(company "Antmicro Ltd")
		(comment 1 "www.antmicro.com")
		(comment 9 "footprints 640-643 of 703")
	)
	(layers
		(0 "F.Cu" signal)
		(4 "In1.Cu" signal)
		(6 "In2.Cu" signal)
		(8 "In3.Cu" signal)
		(10 "In4.Cu" signal)
		(12 "In5.Cu" signal)
		(14 "In6.Cu" signal)
		(2 "B.Cu" signal)
		(9 "F.Adhes" user "F.Adhesive")
		(11 "B.Adhes" user "B.Adhesive")
		(13 "F.Paste" user)
		(15 "B.Paste" user)
		(5 "F.SilkS" user "F.Silkscreen")
		(7 "B.SilkS" user "B.Silkscreen")
		(1 "F.Mask" user)
		(3 "B.Mask" user)
		(17 "Dwgs.User" user "User.Drawings")
		(19 "Cmts.User" user "User.Comments")
		(21 "Eco1.User" user "User.Eco1")
		(23 "Eco2.User" user "User.Eco2")
		(25 "Edge.Cuts" user)
		(27 "Margin" user)
		(31 "F.CrtYd" user "F.Courtyard")
		(29 "B.CrtYd" user "B.Courtyard")
		(35 "F.Fab" user)
		(33 "B.Fab" user)
	)
	(footprint "antmicro-footprints:R_0402_1005Metric"
		(layer "B.Cu")
		(at 136.5 121.15)
		(descr "Resistor SMD 0402")
		(tags "resistor SMD 0402")
		(property "Reference" "R57"
			(at 19.525001 -7.450001 180)
			(layer "B.SilkS")
			(effects
				(font
					(size 0.7 0.7)
					(thickness 0.15)
				)
				(justify mirror)
			)
		)
		(property "Value" "R_100k_0402"
			(at -1.011843 -1.772047 180)
			(layer "B.Fab")
			(effects
				(font
					(size 0.7 0.7)
					(thickness 0.15)
				)
				(justify left bottom mirror)
			)
		)
		(property "Datasheet" "https://www.bourns.com/docs/product-datasheets/cr.pdf"
			(at 0 0 180)
			(layer "B.Fab")
			(hide yes)
			(effects
				(font
					(size 1.27 1.27)
					(thickness 0.15)
				)
				(justify mirror)
			)
		)
		(property "Description" "SMD Chip Resistor, 100 kohm, ± 1%, 62.5 mW, 0402 [1005 Metric], Thick Film, General Purpose"
			(at 0 0 180)
			(layer "B.Fab")
			(hide yes)
			(effects
				(font
					(size 1.27 1.27)
					(thickness 0.15)
				)
				(justify mirror)
			)
		)
		(property "MPN" "CR0402-FX-1003GLF"
			(at 0 0 0)
			(unlocked yes)
			(layer "B.Fab")
			(hide yes)
			(effects
				(font
					(size 1 1)
					(thickness 0.15)
				)
				(justify mirror)
			)
		)
		(property "Manufacturer" "Bourns"
			(at 0 0 0)
			(unlocked yes)
			(layer "B.Fab")
			(hide yes)
			(effects
				(font
					(size 1 1)
					(thickness 0.15)
				)
				(justify mirror)
			)
		)
		(property "License" "Apache-2.0"
			(at 0 0 0)
			(unlocked yes)
			(layer "B.Fab")
			(hide yes)
			(effects
				(font
					(size 1 1)
					(thickness 0.15)
				)
				(justify mirror)
			)
		)
		(property "Val" "100k"
			(at 0 0 0)
			(unlocked yes)
			(layer "B.Fab")
			(hide yes)
			(effects
				(font
					(size 1 1)
					(thickness 0.15)
				)
				(justify mirror)
			)
		)
		(property "Tolerance" "1%"
			(at 0 0 0)
			(unlocked yes)
			(layer "B.Fab")
			(hide yes)
			(effects
				(font
					(size 1 1)
					(thickness 0.15)
				)
				(justify mirror)
			)
		)
		(property "Author" "Antmicro"
			(at 0 0 0)
			(unlocked yes)
			(layer "B.Fab")
			(hide yes)
			(effects
				(font
					(size 1 1)
					(thickness 0.15)
				)
				(justify mirror)
			)
		)
		(sheetname "/TB Controller/")
		(sheetfile "tb.kicad_sch")
		(attr smd)
		(fp_rect
			(start -0.925 0.47)
			(end 0.925 -0.47)
			(stroke
				(width 0.05)
				(type default)
			)
			(fill no)
			(layer "B.CrtYd")
		)
		(fp_rect
			(start -0.5 0.25)
			(end 0.5 -0.25)
			(stroke
				(width 0.15)
				(type solid)
			)
			(fill no)
			(layer "B.Fab")
		)
		(fp_text user "${REFERENCE}"
			(at -0.95 -3.168 180)
			(layer "B.Fab")
			(effects
				(font
					(size 0.7 0.7)
					(thickness 0.15)
				)
				(justify left bottom mirror)
			)
		)
		(fp_text user "Author: Antmicro"
			(at -0.95 -4.169 180)
			(layer "B.Fab")
			(effects
				(font
					(size 0.7 0.7)
					(thickness 0.15)
				)
				(justify left bottom mirror)
			)
		)
		(fp_text user "License: Apache-2.0"
			(at -0.95 -5.169 180)
			(layer "B.Fab")
			(effects
				(font
					(size 0.7 0.7)
					(thickness 0.15)
				)
				(justify left bottom mirror)
			)
		)
		(pad "1" smd roundrect
			(at -0.48 0)
			(size 0.59 0.64)
			(layers "B.Cu" "B.Mask" "B.Paste")
			(roundrect_rratio 0.25)
			(net 371 "/TB Controller/~{PE_WAKE}")
			(pintype "passive")
		)
		(pad "2" smd roundrect
			(at 0.48 0)
			(size 0.59 0.64)
			(layers "B.Cu" "B.Mask" "B.Paste")
			(roundrect_rratio 0.25)
			(net 57 "+3V3_TB")
			(pintype "passive")
		)
	)
	(footprint "antmicro-footprints:TP_SMD_0.75mm"
		(layer "B.Cu")
		(at 183.75 78.75 90)
		(property "Reference" "TP15"
			(at -8.75 0.75 270)
			(layer "B.SilkS")
			(effects
				(font
					(size 0.7 0.7)
					(thickness 0.15)
				)
				(justify left bottom mirror)
			)
		)
		(property "Value" "TP_0.75mm_SMD"
			(at 0 -1.2 270)
			(layer "B.Fab")
			(effects
				(font
					(size 0.7 0.7)
					(thickness 0.15)
				)
				(justify left bottom mirror)
			)
		)
		(property "Description" "SMT test point"
			(at 0 0 270)
			(layer "B.Fab")
			(hide yes)
			(effects
				(font
					(size 1.27 1.27)
					(thickness 0.15)
				)
				(justify mirror)
			)
		)
		(property "MPN" ""
			(at 0 0 90)
			(unlocked yes)
			(layer "B.Fab")
			(hide yes)
			(effects
				(font
					(size 1 1)
					(thickness 0.15)
				)
				(justify mirror)
			)
		)
		(property "Manufacturer" ""
			(at 0 0 90)
			(unlocked yes)
			(layer "B.Fab")
			(hide yes)
			(effects
				(font
					(size 1 1)
					(thickness 0.15)
				)
				(justify mirror)
			)
		)
		(property "Author" "Antmicro"
			(at 0 0 90)
			(unlocked yes)
			(layer "B.Fab")
			(hide yes)
			(effects
				(font
					(size 1 1)
					(thickness 0.15)
				)
				(justify mirror)
			)
		)
		(property "License" "Apache-2.0"
			(at 0 0 90)
			(unlocked yes)
			(layer "B.Fab")
			(hide yes)
			(effects
				(font
					(size 1 1)
					(thickness 0.15)
				)
				(justify mirror)
			)
		)
		(sheetname "/X710 DCDC converters/")
		(sheetfile "DCDC_converters_X710.kicad_sch")
		(attr exclude_from_pos_files exclude_from_bom)
		(fp_circle
			(center 0 0)
			(end 0.475 0)
			(stroke
				(width 0.05)
				(type default)
			)
			(fill no)
			(layer "B.CrtYd")
		)
		(fp_text user "Author: Antmicro"
			(at -0.4 -3.901 270)
			(layer "B.Fab")
			(effects
				(font
					(size 0.7 0.7)
					(thickness 0.15)
				)
				(justify left bottom mirror)
			)
		)
		(fp_text user "License: Apache-2.0"
			(at -0.4 -5.101 270)
			(layer "B.Fab")
			(effects
				(font
					(size 0.7 0.7)
					(thickness 0.15)
				)
				(justify left bottom mirror)
			)
		)
		(fp_text user "${REFERENCE}"
			(at -0.4 -2.7 270)
			(layer "B.Fab")
			(effects
				(font
					(size 0.7 0.7)
					(thickness 0.15)
				)
				(justify left bottom mirror)
			)
		)
		(pad "1" smd circle
			(at 0 0 90)
			(size 0.75 0.75)
			(layers "B.Cu" "B.Mask")
			(net 7 "+3V3")
			(pinfunction "1")
			(pintype "passive")
		)
	)
	(footprint "antmicro-footprints:C_0805_2012Metric"
		(layer "B.Cu")
		(at 159.5 139.25 180)
		(descr "Capacitor SMD 0805")
		(tags "capacitor SMD 0805")
		(property "Reference" "C292"
			(at 2 -0.5 0)
			(layer "B.SilkS")
			(effects
				(font
					(size 0.7 0.7)
					(thickness 0.15)
				)
				(justify left bottom mirror)
			)
		)
		(property "Value" "C_100u_0805"
			(at -2.055717 -1.963152 0)
			(layer "B.Fab")
			(effects
				(font
					(size 0.7 0.7)
					(thickness 0.15)
				)
				(justify left bottom mirror)
			)
		)
		(property "Datasheet" "https://www.murata.com/products/productdetail?partno=GRM21BR60J107ME15%23"
			(at 0 0 0)
			(layer "B.Fab")
			(hide yes)
			(effects
				(font
					(size 1.27 1.27)
					(thickness 0.15)
				)
				(justify mirror)
			)
		)
		(property "Description" "SMD Multilayer Ceramic Capacitor, 100 µF, 6.3 V, 0805 [2012 Metric], ± 20%, X5R, GRM Series"
			(at 0 0 0)
			(layer "B.Fab")
			(hide yes)
			(effects
				(font
					(size 1.27 1.27)
					(thickness 0.15)
				)
				(justify mirror)
			)
		)
		(property "MPN" "GRM21BR60J107ME15L"
			(at 0 0 180)
			(unlocked yes)
			(layer "B.Fab")
			(hide yes)
			(effects
				(font
					(size 1 1)
					(thickness 0.15)
				)
				(justify mirror)
			)
		)
		(property "Manufacturer" "Murata"
			(at 0 0 180)
			(unlocked yes)
			(layer "B.Fab")
			(hide yes)
			(effects
				(font
					(size 1 1)
					(thickness 0.15)
				)
				(justify mirror)
			)
		)
		(property "License" "Apache-2.0"
			(at 0 0 180)
			(unlocked yes)
			(layer "B.Fab")
			(hide yes)
			(effects
				(font
					(size 1 1)
					(thickness 0.15)
				)
				(justify mirror)
			)
		)
		(property "Author" "Antmicro"
			(at 0 0 180)
			(unlocked yes)
			(layer "B.Fab")
			(hide yes)
			(effects
				(font
					(size 1 1)
					(thickness 0.15)
				)
				(justify mirror)
			)
		)
		(property "Val" "100u"
			(at 0 0 180)
			(unlocked yes)
			(layer "B.Fab")
			(hide yes)
			(effects
				(font
					(size 1 1)
					(thickness 0.15)
				)
				(justify mirror)
			)
		)
		(property "Voltage" ""
			(at 0 0 180)
			(unlocked yes)
			(layer "B.Fab")
			(hide yes)
			(effects
				(font
					(size 1 1)
					(thickness 0.15)
				)
				(justify mirror)
			)
		)
		(property "Dielectric" ""
			(at 0 0 180)
			(unlocked yes)
			(layer "B.Fab")
			(hide yes)
			(effects
				(font
					(size 1 1)
					(thickness 0.15)
				)
				(justify mirror)
			)
		)
		(property "Public" "False"
			(at 0 0 180)
			(unlocked yes)
			(layer "B.Fab")
			(hide yes)
			(effects
				(font
					(size 1 1)
					(thickness 0.15)
				)
				(justify mirror)
			)
		)
		(sheetname "/2xRJ45/")
		(sheetfile "2xrj45.kicad_sch")
		(attr smd)
		(fp_line
			(start -0.3 0.7)
			(end 0.3 0.7)
			(stroke
				(width 0.15)
				(type solid)
			)
			(layer "B.SilkS")
		)
		(fp_line
			(start -0.3 -0.7)
			(end 0.3 -0.7)
			(stroke
				(width 0.15)
				(type solid)
			)
			(layer "B.SilkS")
		)
		(fp_rect
			(start 1.95 0.9)
			(end -1.95 -0.9)
			(stroke
				(width 0.05)
				(type default)
			)
			(fill no)
			(layer "B.CrtYd")
		)
		(fp_rect
			(start -0.95 0.675)
			(end 0.95 -0.675)
			(stroke
				(width 0.15)
				(type solid)
			)
			(fill no)
			(layer "B.Fab")
		)
		(fp_text user "${REFERENCE}"
			(at -1.9 -3.947 0)
			(layer "B.Fab")
			(effects
				(font
					(size 0.7 0.7)
					(thickness 0.15)
				)
				(justify left bottom mirror)
			)
		)
		(fp_text user "Author: Antmicro"
			(at -1.9 -5.947 0)
			(layer "B.Fab")
			(effects
				(font
					(size 0.7 0.7)
					(thickness 0.15)
				)
				(justify left bottom mirror)
			)
		)
		(fp_text user "License: Apache-2.0"
			(at -1.9 -4.947 0)
			(layer "B.Fab")
			(effects
				(font
					(size 0.7 0.7)
					(thickness 0.15)
				)
				(justify left bottom mirror)
			)
		)
		(pad "1" smd roundrect
			(at -1.1 0 180)
			(size 1.2 1.3)
			(layers "B.Cu" "B.Mask" "B.Paste")
			(roundrect_rratio 0.25)
			(net 23 "GND")
			(pintype "passive")
		)
		(pad "2" smd roundrect
			(at 1.1 0 180)
			(size 1.2 1.3)
			(layers "B.Cu" "B.Mask" "B.Paste")
			(roundrect_rratio 0.25)
			(net 133 "/2xRJ45/P0_CT")
			(pintype "passive")
		)
	)
	(footprint "antmicro-footprints:SOD-523"
		(layer "B.Cu")
		(at 122.3 150.6 180)
		(property "Reference" "D1"
			(at -0.7 -1.65 0)
			(layer "B.SilkS")
			(effects
				(font
					(size 0.7 0.7)
					(thickness 0.15)
				)
				(justify left bottom mirror)
			)
		)
		(property "Value" "PESD5Z5.0F"
			(at 0 -1.499 0)
			(layer "B.Fab")
			(effects
				(font
					(size 0.7 0.7)
					(thickness 0.15)
				)
				(justify left bottom mirror)
			)
		)
		(property "Datasheet" "https://assets.nexperia.com/documents/data-sheet/PESD5Z5_0.pdf"
			(at 0 0 0)
			(layer "B.Fab")
			(hide yes)
			(effects
				(font
					(size 1.27 1.27)
					(thickness 0.15)
				)
				(justify mirror)
			)
		)
		(property "Description" "Unidirectional TVS, 30 kV,  SOD-523, 5 V, 89 pF"
			(at 0 0 0)
			(layer "B.Fab")
			(hide yes)
			(effects
				(font
					(size 1.27 1.27)
					(thickness 0.15)
				)
				(justify mirror)
			)
		)
		(property "Manufacturer" "Nexperia"
			(at 0 0 180)
			(unlocked yes)
			(layer "B.Fab")
			(hide yes)
			(effects
				(font
					(size 1 1)
					(thickness 0.15)
				)
				(justify mirror)
			)
		)
		(property "MPN" "PESD5Z5.0F"
			(at 0 0 180)
			(unlocked yes)
			(layer "B.Fab")
			(hide yes)
			(effects
				(font
					(size 1 1)
					(thickness 0.15)
				)
				(justify mirror)
			)
		)
		(property "Author" "Antmicro"
			(at 0 0 180)
			(unlocked yes)
			(layer "B.Fab")
			(hide yes)
			(effects
				(font
					(size 1 1)
					(thickness 0.15)
				)
				(justify mirror)
			)
		)
		(property "License" "Apache-2.0"
			(at 0 0 180)
			(unlocked yes)
			(layer "B.Fab")
			(hide yes)
			(effects
				(font
					(size 1 1)
					(thickness 0.15)
				)
				(justify mirror)
			)
		)
		(sheetname "/USB-C connector/")
		(sheetfile "USB-C_connector.kicad_sch")
		(attr smd)
		(fp_line
			(start -0.35 0.5)
			(end -0.35 -0.5)
			(stroke
				(width 0.15)
				(type solid)
			)
			(layer "B.SilkS")
		)
		(fp_rect
			(start -1 0.6)
			(end 1 -0.6)
			(stroke
				(width 0.05)
				(type solid)
			)
			(fill no)
			(layer "B.CrtYd")
		)
		(fp_line
			(start 0.65 0.425)
			(end 0.65 -0.423)
			(stroke
				(width 0.15)
				(type solid)
			)
			(layer "B.Fab")
		)
		(fp_line
			(start -0.35 0.4)
			(end -0.35 -0.4)
			(stroke
				(width 0.15)
				(type solid)
			)
			(layer "B.Fab")
		)
		(fp_line
			(start -0.652 0.425)
			(end 0.65 0.425)
			(stroke
				(width 0.15)
				(type solid)
			)
			(layer "B.Fab")
		)
		(fp_line
			(start -0.652 -0.423)
			(end 0.65 -0.423)
			(stroke
				(width 0.15)
				(type solid)
			)
			(layer "B.Fab")
		)
		(fp_line
			(start -0.652 -0.423)
			(end -0.652 0.425)
			(stroke
				(width 0.15)
				(type solid)
			)
			(layer "B.Fab")
		)
		(fp_text user "Author: Antmicro"
			(at -1.276 -4.7 0)
			(layer "B.Fab")
			(effects
				(font
					(size 0.7 0.7)
					(thickness 0.15)
				)
				(justify left bottom mirror)
			)
		)
		(fp_text user "${REFERENCE}"
			(at -1.276 -3.499 0)
			(layer "B.Fab")
			(effects
				(font
					(size 0.7 0.7)
					(thickness 0.15)
				)
				(justify left bottom mirror)
			)
		)
		(fp_text user "License: Apache-2.0"
			(at -1.276 -5.9 0)
			(layer "B.Fab")
			(effects
				(font
					(size 0.7 0.7)
					(thickness 0.15)
				)
				(justify left bottom mirror)
			)
		)
		(pad "1" smd roundrect
			(at -0.701 0 180)
			(size 0.5 0.6)
			(layers "B.Cu" "B.Mask" "B.Paste")
			(roundrect_rratio 0.25)
			(net 215 "/USB-C connector/VBUS")
			(pinfunction "C")
			(pintype "passive")
		)
		(pad "2" smd roundrect
			(at 0.699 0 180)
			(size 0.5 0.6)
			(layers "B.Cu" "B.Mask" "B.Paste")
			(roundrect_rratio 0.25)
			(net 23 "GND")
			(pinfunction "A")
			(pintype "passive")
		)
	)
)
